(kicad_pcb
	(version 20260206)
	(generator "pcbnew")
	(generator_version "10.0")
	(general
		(thickness 1.6)
		(legacy_teardrops no)
	)
	(paper "A4")
	(title_block
		(title "01162023_DA0F0TEBIF0_F0T_Expander_BD_F_brd_V02_OCP.brd")
		(comment 1 "Grand Teton / footprints 3771-3778 of 9728")
	)
	(layers
		(0 "F.Cu" signal "TOP")
		(4 "In1.Cu" signal "GND")
		(6 "In2.Cu" signal "VCC")
		(8 "In3.Cu" signal "VCC1")
		(10 "In4.Cu" signal "GND1")
		(12 "In5.Cu" signal "IN1")
		(14 "In6.Cu" signal "GND2")
		(16 "In7.Cu" signal "IN2")
		(18 "In8.Cu" signal "GND3")
		(20 "In9.Cu" signal "IN3")
		(22 "In10.Cu" signal "GND4")
		(24 "In11.Cu" signal "IN4")
		(26 "In12.Cu" signal "GND5")
		(28 "In13.Cu" signal "IN5")
		(30 "In14.Cu" signal "GND6")
		(32 "In15.Cu" signal "IN6")
		(34 "In16.Cu" signal "GND7")
		(2 "B.Cu" signal "BOTTOM")
		(9 "F.Adhes" user "F.Adhesive")
		(11 "B.Adhes" user "B.Adhesive")
		(13 "F.Paste" user "Package Geometry/Pastemask Top")
		(15 "B.Paste" user "Package Geometry/Pastemask Bottom")
		(5 "F.SilkS" user "Ref Des/Silkscreen Top")
		(7 "B.SilkS" user "Ref Des/Silkscreen Bottom")
		(1 "F.Mask" user "Board Geometry/Soldermask Top")
		(3 "B.Mask" user "Board Geometry/Soldermask Bottom")
		(17 "Dwgs.User" user "User.Drawings")
		(19 "Cmts.User" user "User.Comments")
		(21 "Eco1.User" user "User.Eco1")
		(23 "Eco2.User" user "User.Eco2")
		(25 "Edge.Cuts" user "Board Geometry/Outline")
		(27 "Margin" user)
		(31 "F.CrtYd" user "Package Geometry/Place Bound Top")
		(29 "B.CrtYd" user "Package Geometry/Place Bound Bottom")
		(35 "F.Fab" user "Ref Des/Assembly Top")
		(33 "B.Fab" user "Ref Des/Assembly Bottom")
	)
	(footprint ""
		(layer "F.Cu")
		(at 384.938524 -112.809782)
		(property "Reference" "C683"
			(at 0 0 0)
			(layer "F.SilkS")
			(hide yes)
			(effects
				(font
					(size 1.27 1.27)
				)
			)
		)
		(property "Value" ""
			(at 0 0 0)
			(layer "F.Fab")
			(effects
				(font
					(size 1.27 1.27)
				)
			)
		)
		(duplicate_pad_numbers_are_jumpers no)
		(fp_line
			(start -0.299974 -0.150114)
			(end 0.299974 -0.150114)
			(stroke
				(width 0.1)
				(type default)
			)
			(layer "F.Fab")
		)
		(fp_line
			(start -0.299974 0.150114)
			(end -0.299974 -0.150114)
			(stroke
				(width 0.1)
				(type default)
			)
			(layer "F.Fab")
		)
		(fp_line
			(start 0.299974 -0.150114)
			(end 0.299974 0.150114)
			(stroke
				(width 0.1)
				(type default)
			)
			(layer "F.Fab")
		)
		(fp_line
			(start 0.299974 0.150114)
			(end -0.299974 0.150114)
			(stroke
				(width 0.1)
				(type default)
			)
			(layer "F.Fab")
		)
		(pad "1" smd rect
			(at -0.2667 0)
			(size 0.3048 0.381)
			(layers "F.Cu" "F.Mask" "F.Paste")
			(net "P5E_PEX3_STN1_TX_DP<23>")
		)
		(pad "2" smd rect
			(at 0.2667 0)
			(size 0.3048 0.381)
			(layers "F.Cu" "F.Mask" "F.Paste")
			(net "P5E_PEX3_STN1_TX_C_DP<23>")
		)
	)
	(footprint ""
		(layer "F.Cu")
		(at 71.65467 -22.867366 90)
		(property "Reference" "C3888"
			(at 0 0 90)
			(layer "F.SilkS")
			(hide yes)
			(effects
				(font
					(size 1.27 1.27)
				)
			)
		)
		(property "Value" ""
			(at 0 0 90)
			(layer "F.Fab")
			(effects
				(font
					(size 1.27 1.27)
				)
			)
		)
		(duplicate_pad_numbers_are_jumpers no)
		(fp_line
			(start 0.7874 -0.4064)
			(end 0.7874 0.4064)
			(stroke
				(width 0.1524)
				(type default)
			)
			(layer "F.SilkS")
		)
		(fp_line
			(start -0.7874 -0.4064)
			(end 0.7874 -0.4064)
			(stroke
				(width 0.1524)
				(type default)
			)
			(layer "F.SilkS")
		)
		(fp_line
			(start 0.7874 0.4064)
			(end -0.7874 0.4064)
			(stroke
				(width 0.1524)
				(type default)
			)
			(layer "F.SilkS")
		)
		(fp_line
			(start -0.7874 0.4064)
			(end -0.7874 -0.4064)
			(stroke
				(width 0.1524)
				(type default)
			)
			(layer "F.SilkS")
		)
		(fp_line
			(start -0.12065 -0.305054)
			(end -0.12065 -0.2794)
			(stroke
				(width 0.1)
				(type default)
			)
			(layer "F.Fab")
		)
		(fp_line
			(start -0.67945 -0.305054)
			(end -0.12065 -0.305054)
			(stroke
				(width 0.1)
				(type default)
			)
			(layer "F.Fab")
		)
		(fp_line
			(start 0.67945 -0.3048)
			(end 0.67945 0.3048)
			(stroke
				(width 0.1)
				(type default)
			)
			(layer "F.Fab")
		)
		(fp_line
			(start 0.12065 -0.3048)
			(end 0.67945 -0.3048)
			(stroke
				(width 0.1)
				(type default)
			)
			(layer "F.Fab")
		)
		(fp_line
			(start 0.12065 -0.2794)
			(end 0.12065 -0.3048)
			(stroke
				(width 0.1)
				(type default)
			)
			(layer "F.Fab")
		)
		(fp_line
			(start -0.12065 -0.2794)
			(end 0.12065 -0.2794)
			(stroke
				(width 0.1)
				(type default)
			)
			(layer "F.Fab")
		)
		(fp_line
			(start 0.120396 0.2794)
			(end -0.12065 0.2794)
			(stroke
				(width 0.1)
				(type default)
			)
			(layer "F.Fab")
		)
		(fp_line
			(start -0.12065 0.2794)
			(end -0.12065 0.3048)
			(stroke
				(width 0.1)
				(type default)
			)
			(layer "F.Fab")
		)
		(fp_line
			(start 0.67945 0.3048)
			(end 0.120396 0.3048)
			(stroke
				(width 0.1)
				(type default)
			)
			(layer "F.Fab")
		)
		(fp_line
			(start 0.120396 0.3048)
			(end 0.120396 0.2794)
			(stroke
				(width 0.1)
				(type default)
			)
			(layer "F.Fab")
		)
		(fp_line
			(start -0.12065 0.3048)
			(end -0.67945 0.3048)
			(stroke
				(width 0.1)
				(type default)
			)
			(layer "F.Fab")
		)
		(fp_line
			(start -0.67945 0.3048)
			(end -0.67945 -0.305054)
			(stroke
				(width 0.1)
				(type default)
			)
			(layer "F.Fab")
		)
		(pad "1" smd circle
			(at -0.40005 0 90)
			(size 0 0)
			(layers "F.Cu" "F.Mask" "F.Paste")
			(net "P12V_SSD2")
		)
		(pad "2" smd circle
			(at 0.40005 0 90)
			(size 0 0)
			(layers "F.Cu" "F.Mask" "F.Paste")
			(net "GND")
		)
	)
	(footprint ""
		(layer "F.Cu")
		(at 275.004022 -350.098614 90)
		(property "Reference" "C608"
			(at 0 0 90)
			(layer "F.SilkS")
			(hide yes)
			(effects
				(font
					(size 1.27 1.27)
				)
			)
		)
		(property "Value" ""
			(at 0 0 90)
			(layer "F.Fab")
			(effects
				(font
					(size 1.27 1.27)
				)
			)
		)
		(duplicate_pad_numbers_are_jumpers no)
		(fp_line
			(start 0.299974 -0.150114)
			(end 0.299974 0.150114)
			(stroke
				(width 0.1)
				(type default)
			)
			(layer "F.Fab")
		)
		(fp_line
			(start -0.299974 -0.150114)
			(end 0.299974 -0.150114)
			(stroke
				(width 0.1)
				(type default)
			)
			(layer "F.Fab")
		)
		(fp_line
			(start 0.299974 0.150114)
			(end -0.299974 0.150114)
			(stroke
				(width 0.1)
				(type default)
			)
			(layer "F.Fab")
		)
		(fp_line
			(start -0.299974 0.150114)
			(end -0.299974 -0.150114)
			(stroke
				(width 0.1)
				(type default)
			)
			(layer "F.Fab")
		)
		(pad "1" smd rect
			(at -0.2667 0 90)
			(size 0.3048 0.381)
			(layers "F.Cu" "F.Mask" "F.Paste")
			(net "P5E_PEX2_STN7_TX_DN<115>")
		)
		(pad "2" smd rect
			(at 0.2667 0 90)
			(size 0.3048 0.381)
			(layers "F.Cu" "F.Mask" "F.Paste")
			(net "P5E_PEX2_STN7_TX_C_DN<115>")
		)
	)
	(footprint ""
		(layer "F.Cu")
		(at 231.887522 -259.813806 180)
		(property "Reference" "C4337"
			(at 0 0 180)
			(layer "F.SilkS")
			(hide yes)
			(effects
				(font
					(size 1.27 1.27)
				)
			)
		)
		(property "Value" ""
			(at 0 0 180)
			(layer "F.Fab")
			(effects
				(font
					(size 1.27 1.27)
				)
			)
		)
		(duplicate_pad_numbers_are_jumpers no)
		(fp_line
			(start 0.299974 0.150114)
			(end -0.299974 0.150114)
			(stroke
				(width 0.1)
				(type default)
			)
			(layer "F.Fab")
		)
		(fp_line
			(start 0.299974 -0.150114)
			(end 0.299974 0.150114)
			(stroke
				(width 0.1)
				(type default)
			)
			(layer "F.Fab")
		)
		(fp_line
			(start -0.299974 0.150114)
			(end -0.299974 -0.150114)
			(stroke
				(width 0.1)
				(type default)
			)
			(layer "F.Fab")
		)
		(fp_line
			(start -0.299974 -0.150114)
			(end 0.299974 -0.150114)
			(stroke
				(width 0.1)
				(type default)
			)
			(layer "F.Fab")
		)
		(pad "1" smd rect
			(at -0.2667 0 180)
			(size 0.3048 0.381)
			(layers "F.Cu" "F.Mask" "F.Paste")
			(net "P1V25_SERDES_VDDPLL_PEX2")
		)
		(pad "2" smd rect
			(at 0.2667 0 180)
			(size 0.3048 0.381)
			(layers "F.Cu" "F.Mask" "F.Paste")
			(net "GND")
		)
	)
	(footprint ""
		(layer "F.Cu")
		(at 221.990158 -80.611472)
		(property "Reference" "R5765"
			(at 0 0 0)
			(layer "F.SilkS")
			(hide yes)
			(effects
				(font
					(size 1.27 1.27)
				)
			)
		)
		(property "Value" ""
			(at 0 0 0)
			(layer "F.Fab")
			(effects
				(font
					(size 1.27 1.27)
				)
			)
		)
		(duplicate_pad_numbers_are_jumpers no)
		(fp_line
			(start -0.7874 -0.4064)
			(end 0.7874 -0.4064)
			(stroke
				(width 0.1524)
				(type default)
			)
			(layer "F.SilkS")
		)
		(fp_line
			(start -0.7874 0.4064)
			(end -0.7874 -0.4064)
			(stroke
				(width 0.1524)
				(type default)
			)
			(layer "F.SilkS")
		)
		(fp_line
			(start 0.7874 -0.4064)
			(end 0.7874 0.4064)
			(stroke
				(width 0.1524)
				(type default)
			)
			(layer "F.SilkS")
		)
		(fp_line
			(start 0.7874 0.4064)
			(end -0.7874 0.4064)
			(stroke
				(width 0.1524)
				(type default)
			)
			(layer "F.SilkS")
		)
		(fp_line
			(start -0.67945 -0.305054)
			(end -0.12065 -0.305054)
			(stroke
				(width 0.1)
				(type default)
			)
			(layer "F.Fab")
		)
		(fp_line
			(start -0.67945 0.3048)
			(end -0.67945 -0.305054)
			(stroke
				(width 0.1)
				(type default)
			)
			(layer "F.Fab")
		)
		(fp_line
			(start -0.12065 -0.305054)
			(end -0.12065 -0.2794)
			(stroke
				(width 0.1)
				(type default)
			)
			(layer "F.Fab")
		)
		(fp_line
			(start -0.12065 -0.2794)
			(end 0.12065 -0.2794)
			(stroke
				(width 0.1)
				(type default)
			)
			(layer "F.Fab")
		)
		(fp_line
			(start -0.12065 0.2794)
			(end -0.12065 0.3048)
			(stroke
				(width 0.1)
				(type default)
			)
			(layer "F.Fab")
		)
		(fp_line
			(start -0.12065 0.3048)
			(end -0.67945 0.3048)
			(stroke
				(width 0.1)
				(type default)
			)
			(layer "F.Fab")
		)
		(fp_line
			(start 0.120396 0.2794)
			(end -0.12065 0.2794)
			(stroke
				(width 0.1)
				(type default)
			)
			(layer "F.Fab")
		)
		(fp_line
			(start 0.120396 0.3048)
			(end 0.120396 0.2794)
			(stroke
				(width 0.1)
				(type default)
			)
			(layer "F.Fab")
		)
		(fp_line
			(start 0.12065 -0.3048)
			(end 0.67945 -0.3048)
			(stroke
				(width 0.1)
				(type default)
			)
			(layer "F.Fab")
		)
		(fp_line
			(start 0.12065 -0.2794)
			(end 0.12065 -0.3048)
			(stroke
				(width 0.1)
				(type default)
			)
			(layer "F.Fab")
		)
		(fp_line
			(start 0.67945 -0.3048)
			(end 0.67945 0.3048)
			(stroke
				(width 0.1)
				(type default)
			)
			(layer "F.Fab")
		)
		(fp_line
			(start 0.67945 0.3048)
			(end 0.120396 0.3048)
			(stroke
				(width 0.1)
				(type default)
			)
			(layer "F.Fab")
		)
		(pad "1" smd circle
			(at -0.40005 0)
			(size 0 0)
			(layers "F.Cu" "F.Mask" "F.Paste")
			(net "SSD11_LED")
		)
		(pad "2" smd circle
			(at 0.40005 0)
			(size 0 0)
			(layers "F.Cu" "F.Mask" "F.Paste")
			(net "SSD11_LED_R")
		)
	)
	(footprint ""
		(layer "F.Cu")
		(at 138.735308 -189.614556)
		(property "Reference" "C4497"
			(at 0 0 0)
			(layer "F.SilkS")
			(hide yes)
			(effects
				(font
					(size 1.27 1.27)
				)
			)
		)
		(property "Value" ""
			(at 0 0 0)
			(layer "F.Fab")
			(effects
				(font
					(size 1.27 1.27)
				)
			)
		)
		(duplicate_pad_numbers_are_jumpers no)
		(fp_line
			(start -0.7874 -0.4064)
			(end 0.7874 -0.4064)
			(stroke
				(width 0.1524)
				(type default)
			)
			(layer "F.SilkS")
		)
		(fp_line
			(start -0.7874 0.4064)
			(end -0.7874 -0.4064)
			(stroke
				(width 0.1524)
				(type default)
			)
			(layer "F.SilkS")
		)
		(fp_line
			(start 0.7874 -0.4064)
			(end 0.7874 0.4064)
			(stroke
				(width 0.1524)
				(type default)
			)
			(layer "F.SilkS")
		)
		(fp_line
			(start 0.7874 0.4064)
			(end -0.7874 0.4064)
			(stroke
				(width 0.1524)
				(type default)
			)
			(layer "F.SilkS")
		)
		(fp_line
			(start -0.67945 -0.305054)
			(end -0.12065 -0.305054)
			(stroke
				(width 0.1)
				(type default)
			)
			(layer "F.Fab")
		)
		(fp_line
			(start -0.67945 0.3048)
			(end -0.67945 -0.305054)
			(stroke
				(width 0.1)
				(type default)
			)
			(layer "F.Fab")
		)
		(fp_line
			(start -0.12065 -0.305054)
			(end -0.12065 -0.2794)
			(stroke
				(width 0.1)
				(type default)
			)
			(layer "F.Fab")
		)
		(fp_line
			(start -0.12065 -0.2794)
			(end 0.12065 -0.2794)
			(stroke
				(width 0.1)
				(type default)
			)
			(layer "F.Fab")
		)
		(fp_line
			(start -0.12065 0.2794)
			(end -0.12065 0.3048)
			(stroke
				(width 0.1)
				(type default)
			)
			(layer "F.Fab")
		)
		(fp_line
			(start -0.12065 0.3048)
			(end -0.67945 0.3048)
			(stroke
				(width 0.1)
				(type default)
			)
			(layer "F.Fab")
		)
		(fp_line
			(start 0.120396 0.2794)
			(end -0.12065 0.2794)
			(stroke
				(width 0.1)
				(type default)
			)
			(layer "F.Fab")
		)
		(fp_line
			(start 0.120396 0.3048)
			(end 0.120396 0.2794)
			(stroke
				(width 0.1)
				(type default)
			)
			(layer "F.Fab")
		)
		(fp_line
			(start 0.12065 -0.3048)
			(end 0.67945 -0.3048)
			(stroke
				(width 0.1)
				(type default)
			)
			(layer "F.Fab")
		)
		(fp_line
			(start 0.12065 -0.2794)
			(end 0.12065 -0.3048)
			(stroke
				(width 0.1)
				(type default)
			)
			(layer "F.Fab")
		)
		(fp_line
			(start 0.67945 -0.3048)
			(end 0.67945 0.3048)
			(stroke
				(width 0.1)
				(type default)
			)
			(layer "F.Fab")
		)
		(fp_line
			(start 0.67945 0.3048)
			(end 0.120396 0.3048)
			(stroke
				(width 0.1)
				(type default)
			)
			(layer "F.Fab")
		)
		(pad "1" smd circle
			(at -0.40005 0)
			(size 0 0)
			(layers "F.Cu" "F.Mask" "F.Paste")
			(net "NIC4_CLK_EN_R_N")
		)
		(pad "2" smd circle
			(at 0.40005 0)
			(size 0 0)
			(layers "F.Cu" "F.Mask" "F.Paste")
			(net "GND")
		)
	)
	(footprint ""
		(layer "F.Cu")
		(at 239.721898 -85.151468 90)
		(property "Reference" "R1015"
			(at 0 0 90)
			(layer "F.SilkS")
			(hide yes)
			(effects
				(font
					(size 1.27 1.27)
				)
			)
		)
		(property "Value" ""
			(at 0 0 90)
			(layer "F.Fab")
			(effects
				(font
					(size 1.27 1.27)
				)
			)
		)
		(duplicate_pad_numbers_are_jumpers no)
		(fp_line
			(start -0.011176 -0.4064)
			(end 0.7874 -0.4064)
			(stroke
				(width 0.1524)
				(type default)
			)
			(layer "F.SilkS")
		)
		(fp_line
			(start -0.009398 0.4064)
			(end -0.7874 0.4064)
			(stroke
				(width 0.1524)
				(type default)
			)
			(layer "F.SilkS")
		)
		(fp_line
			(start -0.12065 -0.305054)
			(end -0.12065 -0.2794)
			(stroke
				(width 0.1)
				(type default)
			)
			(layer "F.Fab")
		)
		(fp_line
			(start -0.67945 -0.305054)
			(end -0.12065 -0.305054)
			(stroke
				(width 0.1)
				(type default)
			)
			(layer "F.Fab")
		)
		(fp_line
			(start 0.67945 -0.3048)
			(end 0.67945 0.3048)
			(stroke
				(width 0.1)
				(type default)
			)
			(layer "F.Fab")
		)
		(fp_line
			(start 0.12065 -0.3048)
			(end 0.67945 -0.3048)
			(stroke
				(width 0.1)
				(type default)
			)
			(layer "F.Fab")
		)
		(fp_line
			(start 0.12065 -0.2794)
			(end 0.12065 -0.3048)
			(stroke
				(width 0.1)
				(type default)
			)
			(layer "F.Fab")
		)
		(fp_line
			(start -0.12065 -0.2794)
			(end 0.12065 -0.2794)
			(stroke
				(width 0.1)
				(type default)
			)
			(layer "F.Fab")
		)
		(fp_line
			(start 0.120396 0.2794)
			(end -0.12065 0.2794)
			(stroke
				(width 0.1)
				(type default)
			)
			(layer "F.Fab")
		)
		(fp_line
			(start -0.12065 0.2794)
			(end -0.12065 0.3048)
			(stroke
				(width 0.1)
				(type default)
			)
			(layer "F.Fab")
		)
		(fp_line
			(start 0.67945 0.3048)
			(end 0.120396 0.3048)
			(stroke
				(width 0.1)
				(type default)
			)
			(layer "F.Fab")
		)
		(fp_line
			(start 0.120396 0.3048)
			(end 0.120396 0.2794)
			(stroke
				(width 0.1)
				(type default)
			)
			(layer "F.Fab")
		)
		(fp_line
			(start -0.12065 0.3048)
			(end -0.67945 0.3048)
			(stroke
				(width 0.1)
				(type default)
			)
			(layer "F.Fab")
		)
		(fp_line
			(start -0.67945 0.3048)
			(end -0.67945 -0.305054)
			(stroke
				(width 0.1)
				(type default)
			)
			(layer "F.Fab")
		)
		(pad "1" smd rect
			(at -0.40005 0 270)
			(size 0.4572 0.508)
			(layers "F.Cu" "F.Mask" "F.Paste")
			(net "USB2_FT4232_CLI_R_DP")
		)
		(pad "2" smd rect
			(at 0.40005 0 270)
			(size 0.4572 0.508)
			(layers "F.Cu" "F.Mask" "F.Paste")
			(net "USB2_FT4232_CLI_DP")
		)
	)
	(footprint ""
		(layer "F.Cu")
		(at 344.261186 -37.951156)
		(property "Reference" "Q228"
			(at -0.040386 -1.874774 0)
			(unlocked yes)
			(layer "F.SilkS")
			(effects
				(font
					(size 0.7874 0.5842)
					(thickness 0.1524)
				)
			)
		)
		(property "Value" ""
			(at 0 0 0)
			(layer "F.Fab")
			(effects
				(font
					(size 1.27 1.27)
				)
			)
		)
		(duplicate_pad_numbers_are_jumpers no)
		(fp_line
			(start -1.376172 -1.199896)
			(end -0.508 -1.199896)
			(stroke
				(width 0.1524)
				(type default)
			)
			(layer "F.SilkS")
		)
		(fp_line
			(start -1.376172 1.199896)
			(end -1.376172 -1.199896)
			(stroke
				(width 0.1524)
				(type default)
			)
			(layer "F.SilkS")
		)
		(fp_line
			(start -0.508 -1.199896)
			(end 0 -0.762)
			(stroke
				(width 0.1524)
				(type default)
			)
			(layer "F.SilkS")
		)
		(fp_line
			(start 0 -0.762)
			(end 0.508 -1.199896)
			(stroke
				(width 0.1524)
				(type default)
			)
			(layer "F.SilkS")
		)
		(fp_line
			(start 0.508 -1.199896)
			(end 1.376172 -1.199896)
			(stroke
				(width 0.1524)
				(type default)
			)
			(layer "F.SilkS")
		)
		(fp_line
			(start 1.376172 -1.199896)
			(end 1.376172 1.199896)
			(stroke
				(width 0.1524)
				(type default)
			)
			(layer "F.SilkS")
		)
		(fp_line
			(start 1.376172 1.199896)
			(end -1.376172 1.199896)
			(stroke
				(width 0.1524)
				(type default)
			)
			(layer "F.SilkS")
		)
		(fp_poly
			(pts
				(xy -1.486662 -0.941578) (xy -1.756156 -1.749806) (xy -2.29489 -1.211072)
			)
			(stroke
				(width 0)
				(type default)
			)
			(fill yes)
			(layer "F.SilkS")
		)
		(fp_line
			(start -0.674878 -1.100074)
			(end 0.674878 -1.100074)
			(stroke
				(width 0.1)
				(type default)
			)
			(layer "F.Fab")
		)
		(fp_line
			(start -0.674878 1.100074)
			(end -0.674878 -1.100074)
			(stroke
				(width 0.1)
				(type default)
			)
			(layer "F.Fab")
		)
		(fp_line
			(start 0.674878 -1.100074)
			(end 0.674878 1.100074)
			(stroke
				(width 0.1)
				(type default)
			)
			(layer "F.Fab")
		)
		(fp_line
			(start 0.674878 1.100074)
			(end -0.674878 1.100074)
			(stroke
				(width 0.1)
				(type default)
			)
			(layer "F.Fab")
		)
		(fp_poly
			(pts
				(xy -1.4605 -0.7493) (xy -2.2225 -1.1303) (xy -2.2225 -0.3683)
			)
			(stroke
				(width 0)
				(type default)
			)
			(fill yes)
			(layer "F.Fab")
		)
		(pad "1" smd rect
			(at -0.899922 -0.750062 270)
			(size 0.6096 0.6096)
			(layers "F.Cu" "F.Mask" "F.Paste")
			(net "GND")
		)
		(pad "2" smd rect
			(at -0.899922 0 270)
			(size 0.4064 0.6096)
			(layers "F.Cu" "F.Mask" "F.Paste")
			(net "P3V3_SSD12_PG_G1")
		)
		(pad "3" smd rect
			(at -0.899922 0.750062 270)
			(size 0.6096 0.6096)
			(layers "F.Cu" "F.Mask" "F.Paste")
			(net "PWRGD_P3V3_SSD12_D")
		)
		(pad "4" smd rect
			(at 0.899922 0.750062 270)
			(size 0.6096 0.6096)
			(layers "F.Cu" "F.Mask" "F.Paste")
			(net "GND")
		)
		(pad "5" smd rect
			(at 0.899922 0 270)
			(size 0.4064 0.6096)
			(layers "F.Cu" "F.Mask" "F.Paste")
			(net "P3V3_SSD12_PG_G2")
		)
		(pad "6" smd rect
			(at 0.899922 -0.750062 270)
			(size 0.6096 0.6096)
			(layers "F.Cu" "F.Mask" "F.Paste")
			(net "P3V3_SSD12_PG_G2")
		)
	)
)
